FILE_TYPE = MACRO_DRAWING;
SET COLOR_WIRE YELLOW;
SET COLOR_PROP MONO;
SET COLOR_DOT WHITE;
SET COLOR_ARC YELLOW;
SET COLOR_BODY GREEN;
SET COLOR_NOTE MONO;
SET PROP_DISPLAY VALUE;
SET PAGE_NUMBER P63;
FORCEADD OFFPAGE..1
(-6100 2250);
FORCEPROP 2 LAST $XR1 29 
J 0
(-6442 2250);
DISPLAY 0.638298 (-6442 2250);
PAINT MONO (-6442 2250);
FORCEPROP 2 LAST $XR0 113 
J 0
(-6352 2250);
DISPLAY 0.638298 (-6352 2250);
PAINT MONO (-6352 2250);
FORCEPROP 2 LAST PATH I10
J 0
(-6050 2325);
DISPLAY 1.021277 (-6050 2325);
PAINT ORANGE (-6050 2325);
DISPLAY INVISIBLE (-6050 2325);
FORCEPROP 1 LAST COMMENT_BODY TRUE
J 0
(-5975 2150);
DISPLAY 0.872340 (-5975 2150);
PAINT GREEN (-5975 2150);
DISPLAY INVISIBLE (-5975 2150);
FORCEPROP 1 LAST OFFPAGE TRUE
J 0
(-5775 2125);
DISPLAY 0.872340 (-5775 2125);
PAINT GREEN (-5775 2125);
DISPLAY INVISIBLE (-5775 2125);
FORCEPROP 2 LAST CDS_LIB mstr_standard
J 0
(-6100 2250);
PAINT ORANGE (-6100 2250);
DISPLAY INVISIBLE (-6100 2250);
FORCEADD OFFPAGE..1
(-6100 2350);
FORCEPROP 2 LAST $XR1 29 
J 0
(-6442 2350);
DISPLAY 0.638298 (-6442 2350);
PAINT MONO (-6442 2350);
FORCEPROP 2 LAST $XR0 113 
J 0
(-6352 2350);
DISPLAY 0.638298 (-6352 2350);
PAINT MONO (-6352 2350);
FORCEPROP 2 LAST PATH I12
J 0
(-6350 2400);
DISPLAY 1.021277 (-6350 2400);
PAINT ORANGE (-6350 2400);
DISPLAY INVISIBLE (-6350 2400);
FORCEPROP 1 LAST COMMENT_BODY TRUE
J 0
(-5975 2250);
DISPLAY 0.872340 (-5975 2250);
PAINT GREEN (-5975 2250);
DISPLAY INVISIBLE (-5975 2250);
FORCEPROP 1 LAST OFFPAGE TRUE
J 0
(-5775 2225);
DISPLAY 0.872340 (-5775 2225);
PAINT GREEN (-5775 2225);
DISPLAY INVISIBLE (-5775 2225);
FORCEPROP 2 LAST CDS_LIB mstr_standard
J 0
(-6100 2350);
PAINT ORANGE (-6100 2350);
DISPLAY INVISIBLE (-6100 2350);
FORCEADD OFFPAGE..1
R 2
(-2050 2900);
FORCEPROP 2 LAST $XR0 103 
J 0
(-1864 2900);
DISPLAY 0.638298 (-1864 2900);
PAINT MONO (-1864 2900);
FORCEPROP 2 LAST PATH I15
J 0
(-1875 2975);
DISPLAY 1.021277 (-1875 2975);
PAINT ORANGE (-1875 2975);
DISPLAY INVISIBLE (-1875 2975);
FORCEPROP 1 LAST COMMENT_BODY TRUE
J 2
(-2175 2800);
DISPLAY 0.872340 (-2175 2800);
PAINT GREEN (-2175 2800);
DISPLAY INVISIBLE (-2175 2800);
FORCEPROP 1 LAST OFFPAGE TRUE
J 2
(-2375 2775);
DISPLAY 0.872340 (-2375 2775);
PAINT GREEN (-2375 2775);
DISPLAY INVISIBLE (-2375 2775);
FORCEPROP 2 LAST CDS_LIB mstr_standard
J 2
(-2050 2900);
PAINT ORANGE (-2050 2900);
DISPLAY INVISIBLE (-2050 2900);
FORCEADD OFFPAGE..1
R 2
(-2050 2850);
FORCEPROP 2 LAST $XR0 103 
J 0
(-1864 2850);
DISPLAY 0.638298 (-1864 2850);
PAINT MONO (-1864 2850);
FORCEPROP 2 LAST PATH I16
J 0
(-1875 2925);
DISPLAY 1.021277 (-1875 2925);
PAINT ORANGE (-1875 2925);
DISPLAY INVISIBLE (-1875 2925);
FORCEPROP 1 LAST COMMENT_BODY TRUE
J 2
(-2175 2750);
DISPLAY 0.872340 (-2175 2750);
PAINT GREEN (-2175 2750);
DISPLAY INVISIBLE (-2175 2750);
FORCEPROP 1 LAST OFFPAGE TRUE
J 2
(-2375 2725);
DISPLAY 0.872340 (-2375 2725);
PAINT GREEN (-2375 2725);
DISPLAY INVISIBLE (-2375 2725);
FORCEPROP 2 LAST CDS_LIB mstr_standard
J 2
(-2050 2850);
PAINT ORANGE (-2050 2850);
DISPLAY INVISIBLE (-2050 2850);
FORCEADD OFFPAGE..1
(-6100 2900);
FORCEPROP 2 LAST $XR0 104 
J 0
(-6352 2900);
DISPLAY 0.638298 (-6352 2900);
PAINT MONO (-6352 2900);
FORCEPROP 2 LAST PATH I20
J 0
(-6050 2975);
DISPLAY 1.021277 (-6050 2975);
PAINT ORANGE (-6050 2975);
DISPLAY INVISIBLE (-6050 2975);
FORCEPROP 1 LAST COMMENT_BODY TRUE
J 0
(-5975 2800);
DISPLAY 0.872340 (-5975 2800);
PAINT GREEN (-5975 2800);
DISPLAY INVISIBLE (-5975 2800);
FORCEPROP 1 LAST OFFPAGE TRUE
J 0
(-5775 2775);
DISPLAY 0.872340 (-5775 2775);
PAINT GREEN (-5775 2775);
DISPLAY INVISIBLE (-5775 2775);
FORCEPROP 2 LAST CDS_LIB mstr_standard
J 0
(-6100 2900);
PAINT ORANGE (-6100 2900);
DISPLAY INVISIBLE (-6100 2900);
FORCEADD OFFPAGE..1
(-6100 2850);
FORCEPROP 2 LAST $XR0 104 
J 0
(-6352 2850);
DISPLAY 0.638298 (-6352 2850);
PAINT MONO (-6352 2850);
FORCEPROP 2 LAST PATH I21
J 0
(-6050 2925);
DISPLAY 1.021277 (-6050 2925);
PAINT ORANGE (-6050 2925);
DISPLAY INVISIBLE (-6050 2925);
FORCEPROP 1 LAST COMMENT_BODY TRUE
J 0
(-5975 2750);
DISPLAY 0.872340 (-5975 2750);
PAINT GREEN (-5975 2750);
DISPLAY INVISIBLE (-5975 2750);
FORCEPROP 1 LAST OFFPAGE TRUE
J 0
(-5775 2725);
DISPLAY 0.872340 (-5775 2725);
PAINT GREEN (-5775 2725);
DISPLAY INVISIBLE (-5775 2725);
FORCEPROP 2 LAST CDS_LIB mstr_standard
J 0
(-6100 2850);
PAINT ORANGE (-6100 2850);
DISPLAY INVISIBLE (-6100 2850);
FORCEADD OFFPAGE..1
R 2
(-2050 2300);
FORCEPROP 2 LAST $XR1 192 
J 0
(-1864 2264);
DISPLAY 0.638298 (-1864 2264);
PAINT MONO (-1864 2264);
FORCEPROP 2 LAST $XR0 190 
J 0
(-1864 2300);
DISPLAY 0.638298 (-1864 2300);
PAINT MONO (-1864 2300);
FORCEPROP 2 LAST PATH I22
J 0
(-1875 2375);
DISPLAY 1.021277 (-1875 2375);
PAINT ORANGE (-1875 2375);
DISPLAY INVISIBLE (-1875 2375);
FORCEPROP 1 LAST COMMENT_BODY TRUE
J 2
(-2175 2200);
DISPLAY 0.872340 (-2175 2200);
PAINT GREEN (-2175 2200);
DISPLAY INVISIBLE (-2175 2200);
FORCEPROP 1 LAST OFFPAGE TRUE
J 2
(-2375 2175);
DISPLAY 0.872340 (-2375 2175);
PAINT GREEN (-2375 2175);
DISPLAY INVISIBLE (-2375 2175);
FORCEPROP 2 LAST CDS_LIB mstr_standard
J 0
(-2050 2300);
PAINT MONO (-2050 2300);
DISPLAY INVISIBLE (-2050 2300);
FORCEADD SKX_EXT_B..9
(-4075 2500);
FORCEPROP 2 LASTPIN (-3125 1750) $PN AT25
J 0
(-3115 1760);
DISPLAY 0.617021 (-3115 1760);
PAINT ORANGE (-3115 1760);
FORCEPROP 1 LAST LOCATION U2D1
J 0
(-4975 3650);
DISPLAY 0.617021 (-4975 3650);
PAINT AQUA (-4975 3650);
FORCEPROP 1 LAST PART_NUMBER TBD
J 0
(-4975 1350);
DISPLAY 0.617021 (-4975 1350);
PAINT BLUE (-4975 1350);
FORCEPROP 1 LAST MATERIAL IC
J 0
(-4975 3600);
DISPLAY 0.617021 (-4975 3600);
PAINT SKYBLUE (-4975 3600);
FORCEPROP 2 LASTPIN (-3125 2100) $PN AR20
J 0
(-3115 2110);
DISPLAY 0.617021 (-3115 2110);
PAINT ORANGE (-3115 2110);
FORCEPROP 2 LASTPIN (-3125 2050) $PN AR22
J 0
(-3115 2060);
DISPLAY 0.617021 (-3115 2060);
PAINT ORANGE (-3115 2060);
FORCEPROP 2 LASTPIN (-3125 1950) $PN AR26
J 0
(-3115 1960);
DISPLAY 0.617021 (-3115 1960);
PAINT ORANGE (-3115 1960);
FORCEPROP 2 LASTPIN (-3125 1900) $PN AR62
J 0
(-3115 1910);
DISPLAY 0.617021 (-3115 1910);
PAINT ORANGE (-3115 1910);
FORCEPROP 2 LASTPIN (-3125 1850) $PN AT13
J 0
(-3115 1860);
DISPLAY 0.617021 (-3115 1860);
PAINT ORANGE (-3115 1860);
FORCEPROP 2 LASTPIN (-3125 1800) $PN AT23
J 0
(-3115 1810);
DISPLAY 0.617021 (-3115 1810);
PAINT ORANGE (-3115 1810);
FORCEPROP 2 LASTPIN (-3125 1700) $PN AV77
J 0
(-3115 1710);
DISPLAY 0.617021 (-3115 1710);
PAINT ORANGE (-3115 1710);
FORCEPROP 2 LASTPIN (-3125 1650) $PN AW64
J 0
(-3115 1660);
DISPLAY 0.617021 (-3115 1660);
PAINT ORANGE (-3115 1660);
FORCEPROP 2 LASTPIN (-5025 2100) $PN AW76
J 2
(-5035 2110);
DISPLAY 0.617021 (-5035 2110);
PAINT ORANGE (-5035 2110);
FORCEPROP 2 LASTPIN (-5025 2050) $PN AY65
J 2
(-5035 2060);
DISPLAY 0.617021 (-5035 2060);
PAINT ORANGE (-5035 2060);
FORCEPROP 2 LASTPIN (-5025 1950) $PN AY67
J 2
(-5035 1960);
DISPLAY 0.617021 (-5035 1960);
PAINT ORANGE (-5035 1960);
FORCEPROP 2 LASTPIN (-5025 1900) $PN AY75
J 2
(-5035 1910);
DISPLAY 0.617021 (-5035 1910);
PAINT ORANGE (-5035 1910);
FORCEPROP 2 LASTPIN (-5025 1850) $PN AY77
J 2
(-5035 1860);
DISPLAY 0.617021 (-5035 1860);
PAINT ORANGE (-5035 1860);
FORCEPROP 2 LASTPIN (-5025 1800) $PN BA14
J 2
(-5035 1810);
DISPLAY 0.617021 (-5035 1810);
PAINT ORANGE (-5035 1810);
FORCEPROP 2 LASTPIN (-5025 1750) $PN BA16
J 2
(-5035 1760);
DISPLAY 0.617021 (-5035 1760);
PAINT ORANGE (-5035 1760);
FORCEPROP 2 LASTPIN (-5025 1700) $PN BA18
J 2
(-5035 1710);
DISPLAY 0.617021 (-5035 1710);
PAINT ORANGE (-5035 1710);
FORCEPROP 2 LASTPIN (-5025 1650) $PN BA22
J 2
(-5035 1660);
DISPLAY 0.617021 (-5035 1660);
PAINT ORANGE (-5035 1660);
FORCEPROP 2 LASTPIN (-5025 1600) $PN BA64
J 2
(-5035 1610);
DISPLAY 0.617021 (-5035 1610);
PAINT ORANGE (-5035 1610);
FORCEPROP 2 LASTPIN (-3125 1600) $PN BA66
J 0
(-3115 1610);
DISPLAY 0.617021 (-3115 1610);
PAINT ORANGE (-3115 1610);
FORCEPROP 2 LASTPIN (-3125 1550) $PN BA76
J 0
(-3115 1560);
DISPLAY 0.617021 (-3115 1560);
PAINT ORANGE (-3115 1560);
FORCEPROP 2 LASTPIN (-3125 3400) $PN CR4
J 0
(-3115 3410);
DISPLAY 0.617021 (-3115 3410);
PAINT ORANGE (-3115 3410);
FORCEPROP 2 LASTPIN (-3125 3350) $PN CM3
J 0
(-3115 3360);
DISPLAY 0.617021 (-3115 3360);
PAINT ORANGE (-3115 3360);
FORCEPROP 2 LASTPIN (-3125 3300) $PN CL4
J 0
(-3115 3310);
DISPLAY 0.617021 (-3115 3310);
PAINT ORANGE (-3115 3310);
FORCEPROP 2 LASTPIN (-3125 3250) $PN CH5
J 0
(-3115 3260);
DISPLAY 0.617021 (-3115 3260);
PAINT ORANGE (-3115 3260);
FORCEPROP 2 LASTPIN (-3125 3150) $PN CP5
J 0
(-3115 3160);
DISPLAY 0.617021 (-3115 3160);
PAINT ORANGE (-3115 3160);
FORCEPROP 2 LASTPIN (-3125 3100) $PN CN4
J 0
(-3115 3110);
DISPLAY 0.617021 (-3115 3110);
PAINT ORANGE (-3115 3110);
FORCEPROP 2 LASTPIN (-3125 3050) $PN CJ4
J 0
(-3115 3060);
DISPLAY 0.617021 (-3115 3060);
PAINT ORANGE (-3115 3060);
FORCEPROP 2 LASTPIN (-3125 3000) $PN CG4
J 0
(-3115 3010);
DISPLAY 0.617021 (-3115 3010);
PAINT ORANGE (-3115 3010);
FORCEPROP 2 LASTPIN (-5025 3400) $PN CV11
J 2
(-5035 3410);
DISPLAY 0.617021 (-5035 3410);
PAINT ORANGE (-5035 3410);
FORCEPROP 2 LASTPIN (-5025 3350) $PN CP11
J 2
(-5035 3360);
DISPLAY 0.617021 (-5035 3360);
PAINT ORANGE (-5035 3360);
FORCEPROP 2 LASTPIN (-5025 3300) $PN CN10
J 2
(-5035 3310);
DISPLAY 0.617021 (-5035 3310);
PAINT ORANGE (-5035 3310);
FORCEPROP 2 LASTPIN (-5025 3250) $PN CL10
J 2
(-5035 3260);
DISPLAY 0.617021 (-5035 3260);
PAINT ORANGE (-5035 3260);
FORCEPROP 2 LASTPIN (-5025 3150) $PN CT11
J 2
(-5035 3160);
DISPLAY 0.617021 (-5035 3160);
PAINT ORANGE (-5035 3160);
FORCEPROP 2 LASTPIN (-5025 3100) $PN CR12
J 2
(-5035 3110);
DISPLAY 0.617021 (-5035 3110);
PAINT ORANGE (-5035 3110);
FORCEPROP 2 LASTPIN (-5025 3050) $PN CM11
J 2
(-5035 3060);
DISPLAY 0.617021 (-5035 3060);
PAINT ORANGE (-5035 3060);
FORCEPROP 2 LASTPIN (-5025 3000) $PN CK9
J 2
(-5035 3010);
DISPLAY 0.617021 (-5035 3010);
PAINT ORANGE (-5035 3010);
FORCEPROP 2 LASTPIN (-5025 2200) $PN CD23
J 2
(-5035 2210);
DISPLAY 0.617021 (-5035 2210);
PAINT ORANGE (-5035 2210);
FORCEPROP 2 LASTPIN (-5025 2250) $PN CE24
J 2
(-5035 2260);
DISPLAY 0.617021 (-5035 2260);
PAINT ORANGE (-5035 2260);
FORCEPROP 2 LASTPIN (-3125 2200) $PN CC22
J 0
(-3115 2210);
DISPLAY 0.617021 (-3115 2210);
PAINT ORANGE (-3115 2210);
FORCEPROP 2 LASTPIN (-5025 2300) $PN BY21
J 2
(-5035 2310);
DISPLAY 0.617021 (-5035 2310);
PAINT ORANGE (-5035 2310);
FORCEPROP 2 LASTPIN (-5025 2350) $PN CB23
J 2
(-5035 2360);
DISPLAY 0.617021 (-5035 2360);
PAINT ORANGE (-5035 2360);
FORCEPROP 2 LASTPIN (-3125 2300) $PN CF25
J 0
(-3115 2310);
DISPLAY 0.617021 (-3115 2310);
PAINT ORANGE (-3115 2310);
FORCEPROP 2 LASTPIN (-3125 2900) $PN BW24
J 0
(-3115 2910);
DISPLAY 0.617021 (-3115 2910);
PAINT ORANGE (-3115 2910);
FORCEPROP 2 LASTPIN (-3125 2850) $PN BU24
J 0
(-3115 2860);
DISPLAY 0.617021 (-3115 2860);
PAINT ORANGE (-3115 2860);
FORCEPROP 2 LASTPIN (-5025 2850) $PN BE16
J 2
(-5035 2860);
DISPLAY 0.617021 (-5035 2860);
PAINT ORANGE (-5035 2860);
FORCEPROP 2 LASTPIN (-3125 2750) $PN BK23
J 0
(-3115 2760);
DISPLAY 0.617021 (-3115 2760);
PAINT ORANGE (-3115 2760);
FORCEPROP 2 LASTPIN (-3125 2700) $PN BT19
J 0
(-3115 2710);
DISPLAY 0.617021 (-3115 2710);
PAINT ORANGE (-3115 2710);
FORCEPROP 2 LASTPIN (-3125 2650) $PN BM23
J 0
(-3115 2660);
DISPLAY 0.617021 (-3115 2660);
PAINT ORANGE (-3115 2660);
FORCEPROP 2 LASTPIN (-3125 2600) $PN BM21
J 0
(-3115 2610);
DISPLAY 0.617021 (-3115 2610);
PAINT ORANGE (-3115 2610);
FORCEPROP 2 LASTPIN (-3125 2450) $PN BH23
J 0
(-3115 2460);
DISPLAY 0.617021 (-3115 2460);
PAINT ORANGE (-3115 2460);
FORCEPROP 2 LASTPIN (-3125 2500) $PN BJ22
J 0
(-3115 2510);
DISPLAY 0.617021 (-3115 2510);
PAINT ORANGE (-3115 2510);
FORCEPROP 2 LASTPIN (-5025 2750) $PN BN24
J 2
(-5035 2760);
DISPLAY 0.617021 (-5035 2760);
PAINT ORANGE (-5035 2760);
FORCEPROP 2 LASTPIN (-5025 2700) $PN BR20
J 2
(-5035 2710);
DISPLAY 0.617021 (-5035 2710);
PAINT ORANGE (-5035 2710);
FORCEPROP 2 LASTPIN (-5025 2650) $PN BK21
J 2
(-5035 2660);
DISPLAY 0.617021 (-5035 2660);
PAINT ORANGE (-5035 2660);
FORCEPROP 2 LASTPIN (-5025 2600) $PN BP19
J 2
(-5035 2610);
DISPLAY 0.617021 (-5035 2610);
PAINT ORANGE (-5035 2610);
FORCEPROP 2 LASTPIN (-5025 2450) $PN BP23
J 2
(-5035 2460);
DISPLAY 0.617021 (-5035 2460);
PAINT ORANGE (-5035 2460);
FORCEPROP 2 LASTPIN (-5025 2500) $PN BN22
J 2
(-5035 2510);
DISPLAY 0.617021 (-5035 2510);
PAINT ORANGE (-5035 2510);
FORCEPROP 2 LASTPIN (-5025 2900) $PN BG16
J 2
(-5035 2910);
DISPLAY 0.617021 (-5035 2910);
PAINT ORANGE (-5035 2910);
FORCEPROP 1 LAST PACK_TYPE BGA1
J 0
(-4975 3700);
PAINT SKYBLUE (-4975 3700);
DISPLAY INVISIBLE (-4975 3700);
FORCEPROP 2 LAST SEC_TYPE BGA1
J 0
(-4975 3700);
DISPLAY 1.021277 (-4975 3700);
PAINT ORANGE (-4975 3700);
DISPLAY INVISIBLE (-4975 3700);
FORCEPROP 2 LAST CDS_LIB chpset_lib
J 0
(-4075 2500);
PAINT ORANGE (-4075 2500);
DISPLAY INVISIBLE (-4075 2500);
FORCEPROP 2 LAST SEC 9
J 0
(-4975 3700);
DISPLAY 0.680851 (-4975 3700);
PAINT MONO (-4975 3700);
DISPLAY INVISIBLE (-4975 3700);
FORCEPROP 2 LAST CDS_LOCATION U2D1
J 0
(-4975 3650);
DISPLAY 0.617021 (-4975 3650);
PAINT AQUA (-4975 3650);
DISPLAY INVISIBLE (-4975 3650);
FORCEPROP 1 LAST PATH I23
J 0
(-4075 3600);
PAINT GREEN (-4075 3600);
DISPLAY INVISIBLE (-4075 3600);
FORCEADD OFFPAGE..1
(-6100 2200);
FORCEPROP 2 LAST $XR1 29 
J 0
(-6442 2200);
DISPLAY 0.638298 (-6442 2200);
PAINT MONO (-6442 2200);
FORCEPROP 2 LAST $XR0 113 
J 0
(-6352 2200);
DISPLAY 0.638298 (-6352 2200);
PAINT MONO (-6352 2200);
FORCEPROP 2 LAST PATH I26
J 0
(-6050 2275);
DISPLAY 1.021277 (-6050 2275);
PAINT ORANGE (-6050 2275);
DISPLAY INVISIBLE (-6050 2275);
FORCEPROP 1 LAST COMMENT_BODY TRUE
J 0
(-5975 2100);
DISPLAY 0.872340 (-5975 2100);
PAINT GREEN (-5975 2100);
DISPLAY INVISIBLE (-5975 2100);
FORCEPROP 1 LAST OFFPAGE TRUE
J 0
(-5775 2075);
DISPLAY 0.872340 (-5775 2075);
PAINT GREEN (-5775 2075);
DISPLAY INVISIBLE (-5775 2075);
FORCEPROP 2 LAST CDS_LIB mstr_standard
J 0
(-6100 2200);
PAINT MONO (-6100 2200);
DISPLAY INVISIBLE (-6100 2200);
FORCEADD VCC_CORE..1
(-1425 2250);
FORCEPROP 3 LASTPIN (-1425 2200) SIG_NAME PVCCMCP_CPU1\g
J 0
(-1415 2210);
DISPLAY 0.659574 (-1415 2210);
PAINT MONO (-1415 2210);
DISPLAY INVISIBLE (-1415 2210);
FORCEPROP 1 LAST HDL_POWER PVCCMCP_CPU1
J 1
(-1425 2300);
DISPLAY 0.617021 (-1425 2300);
PAINT GREEN (-1425 2300);
FORCEPROP 2 LAST CDS_LIB mstr_symbols
J 0
(-1425 2250);
PAINT ORANGE (-1425 2250);
DISPLAY INVISIBLE (-1425 2250);
FORCEPROP 1 LAST PATH I27
J 0
(-1375 2275);
DISPLAY 0.872340 (-1375 2275);
PAINT AQUA (-1375 2275);
DISPLAY INVISIBLE (-1375 2275);
FORCEADD OFFPAGE..2
(-2050 2200);
FORCEPROP 2 LAST $XR0 113 
J 0
(-1861 2200);
DISPLAY 0.638298 (-1861 2200);
PAINT MONO (-1861 2200);
FORCEPROP 2 LAST PATH I7
J 0
(-1875 2275);
DISPLAY 1.021277 (-1875 2275);
PAINT ORANGE (-1875 2275);
DISPLAY INVISIBLE (-1875 2275);
FORCEPROP 1 LAST COMMENT_BODY TRUE
J 0
(-2095 2105);
DISPLAY 1.404255 (-2095 2105);
PAINT PEACH (-2095 2105);
DISPLAY INVISIBLE (-2095 2105);
FORCEPROP 1 LAST OFFPAGE TRUE
J 0
(-1725 2075);
PAINT GREEN (-1725 2075);
DISPLAY INVISIBLE (-1725 2075);
FORCEPROP 2 LAST CDS_LIB mstr_standard
J 0
(-2050 2200);
PAINT ORANGE (-2050 2200);
DISPLAY INVISIBLE (-2050 2200);
FORCEADD OFFPAGE..1
(-6100 2300);
FORCEPROP 2 LAST $XR0 113 
J 0
(-6352 2300);
DISPLAY 0.638298 (-6352 2300);
PAINT MONO (-6352 2300);
FORCEPROP 2 LAST PATH I9
J 0
(-6050 2375);
DISPLAY 1.021277 (-6050 2375);
PAINT ORANGE (-6050 2375);
DISPLAY INVISIBLE (-6050 2375);
FORCEPROP 1 LAST COMMENT_BODY TRUE
J 0
(-5975 2200);
DISPLAY 0.872340 (-5975 2200);
PAINT GREEN (-5975 2200);
DISPLAY INVISIBLE (-5975 2200);
FORCEPROP 1 LAST OFFPAGE TRUE
J 0
(-5775 2175);
DISPLAY 0.872340 (-5775 2175);
PAINT GREEN (-5775 2175);
DISPLAY INVISIBLE (-5775 2175);
FORCEPROP 2 LAST CDS_LIB mstr_standard
J 0
(-6100 2300);
PAINT ORANGE (-6100 2300);
DISPLAY INVISIBLE (-6100 2300);
FORCEADD DESIGN_NOTE..1
(-4800 1175);
FORCEPROP 0 LAST L1 CPU SYMBOLS 1-30 ARE PRELIMINARY AND SUBJECT TO CHANGE
J 0
(-5000 1050);
DISPLAY 1.021277 (-5000 1050);
PAINT ORANGE (-5000 1050);
FORCEPROP 2 LAST CDS_LIB mstr_symbols
J 0
(-4800 1175);
PAINT ORANGE (-4800 1175);
DISPLAY INVISIBLE (-4800 1175);
FORCEPROP 1 LAST COMMENT_BODY TRUE
J 0
(-4775 1275);
DISPLAY 0.978723 (-4775 1275);
PAINT ORANGE (-4775 1275);
DISPLAY INVISIBLE (-4775 1275);
FORCEADD INTEL_CORP_BPAGE..1
(0 0);
FORCEPROP 1 LAST CDS_CON_LAST_MODIFIED Fri Jun 16 17:48:24 2017
J 0
(-1425 325);
DISPLAY 1.340426 (-1425 325);
PAINT GREEN (-1425 325);
DISPLAY INVISIBLE (-1425 325);
FORCEPROP 1 LAST CUSTOM_TXT_CDS <CURRENT_DESIGN_SHEET> OF <TOTAL_DESIGN_SHEETS>
J 0
(-500 25);
PAINT ORANGE (-500 25);
FORCEPROP 1 LAST CUSTOM_TXT_CDS <CON_LAST_MODIFIED>
J 0
(-4000 100);
PAINT ORANGE (-4000 100);
FORCEPROP 2 LAST CUSTOM_TXT_CDS <XR_PAGE_TITLE>
J 0
(-7890 5250);
DISPLAY 0.638298 (-7890 5250);
PAINT PINK (-7890 5250);
DISPLAY INVISIBLE (-7890 5250);
FORCEPROP 1 LAST SCH_TITLE SKYLAKE - SKT1 - 9 OF 21
J 0
(-7950 50);
DISPLAY 1.212766 (-7950 50);
PAINT GREEN (-7950 50);
FORCEPROP 2 LAST CDS_LIB mstr_symbols
J 0
(0 0);
PAINT ORANGE (0 0);
DISPLAY INVISIBLE (0 0);
FORCEPROP 2 LAST PAGE_BORDER TRUE
J 0
(-7890 5250);
DISPLAY 0.851064 (-7890 5250);
PAINT PINK (-7890 5250);
DISPLAY INVISIBLE (-7890 5250);
FORCEPROP 1 LAST COMMENT_BODY TRUE
J 0
(12 12);
DISPLAY 0.638298 (12 12);
PAINT GREEN (12 12);
DISPLAY INVISIBLE (12 12);
FORCEPROP 2 LAST CDS_XR_PAGE_TITLE CR-63 : @BASEBOARD_FAB2_LIB.BASEBOARD_FAB2(SCH_1):PAGE63
J 0
(-7890 5250);
DISPLAY 0.638298 (-7890 5250);
PAINT PINK (-7890 5250);
DISPLAY INVISIBLE (-7890 5250);
FORCEADD PRELIM..10
(-4065 2490);
PAINT GRAY (-4065 2490);
FORCEPROP 2 LAST CDS_LIB mstr_misc
J 0
(-4065 2490);
PAINT ORANGE (-4065 2490);
DISPLAY INVISIBLE (-4065 2490);
FORCEPROP 1 LAST COMMENT_BODY TRUE
J 0
(-4065 2490);
PAINT ORANGE (-4065 2490);
DISPLAY INVISIBLE (-4065 2490);
WIRE 16 -1 (-1425 2100)(-1425 2200);
WIRE 16 -1 (-1425 1800)(-1425 2100);
WIRE 16 -1 (-1425 2100)(-3000 2100);
WIRE 16 -1 (-3000 2050)(-3000 2100);
WIRE 16 -1 (-3125 2100)(-3000 2100);
WIRE 16 -1 (-3000 1800)(-1425 1800);
WIRE 16 -1 (-3000 1750)(-3000 1800);
WIRE 16 -1 (-3125 1800)(-3000 1800);
WIRE 16 -1 (-3000 1950)(-3000 2050);
WIRE 16 -1 (-3125 2050)(-3000 2050);
WIRE 16 -1 (-3125 1950)(-3000 1950);
WIRE 16 -1 (-3125 1750)(-3000 1750);
WIRE 16 -1 (-2100 3250)(-3125 3250);
FORCEPROP 0 LAST SIG_NAME TP_CPU1_DMI_TX_DP0
J 0
(-2935 3260);
DISPLAY 0.617021 (-2935 3260);
PAINT ORANGE (-2935 3260);
FORCEPROP 2 LASTPROP $XRERR UNIQUE?
J 0
(-2070 3250);
DISPLAY 0.638298 (-2070 3250);
PAINT MONO (-2070 3250);
DISPLAY INVISIBLE (-2070 3250);
WIRE 16 -1 (-3125 3350)(-2100 3350);
FORCEPROP 0 LAST SIG_NAME TP_CPU1_DMI_TX_DP2
J 0
(-2935 3360);
DISPLAY 0.617021 (-2935 3360);
PAINT ORANGE (-2935 3360);
FORCEPROP 2 LASTPROP $XRERR UNIQUE?
J 0
(-2070 3350);
DISPLAY 0.638298 (-2070 3350);
PAINT MONO (-2070 3350);
DISPLAY INVISIBLE (-2070 3350);
WIRE 16 -1 (-2100 1550)(-3125 1550);
FORCEPROP 2 LAST SIG_NAME TP_CPU1_RSVD_172
J 0
(-2950 1560);
DISPLAY 0.617021 (-2950 1560);
PAINT ORANGE (-2950 1560);
FORCEPROP 2 LASTPROP $XRERR UNIQUE?
J 0
(-2070 1550);
DISPLAY 0.638298 (-2070 1550);
PAINT MONO (-2070 1550);
DISPLAY INVISIBLE (-2070 1550);
WIRE 16 -1 (-6050 3250)(-5025 3250);
FORCEPROP 0 LAST SIG_NAME TP_CPU1_DMI_RX_DP0
J 0
(-5985 3260);
DISPLAY 0.617021 (-5985 3260);
PAINT ORANGE (-5985 3260);
FORCEPROP 2 LASTPROP $XRERR UNIQUE?
J 0
(-6290 3250);
DISPLAY 0.638298 (-6290 3250);
PAINT MONO (-6290 3250);
DISPLAY INVISIBLE (-6290 3250);
WIRE 16 -1 (-6050 3400)(-5025 3400);
FORCEPROP 0 LAST SIG_NAME TP_CPU1_DMI_RX_DP3
J 0
(-5985 3410);
DISPLAY 0.617021 (-5985 3410);
PAINT ORANGE (-5985 3410);
FORCEPROP 2 LASTPROP $XRERR UNIQUE?
J 0
(-6290 3400);
DISPLAY 0.638298 (-6290 3400);
PAINT MONO (-6290 3400);
DISPLAY INVISIBLE (-6290 3400);
WIRE 16 -1 (-6050 3300)(-5025 3300);
FORCEPROP 0 LAST SIG_NAME TP_CPU1_DMI_RX_DP1
J 0
(-5985 3310);
DISPLAY 0.617021 (-5985 3310);
PAINT ORANGE (-5985 3310);
FORCEPROP 2 LASTPROP $XRERR UNIQUE?
J 0
(-6290 3300);
DISPLAY 0.638298 (-6290 3300);
PAINT MONO (-6290 3300);
DISPLAY INVISIBLE (-6290 3300);
WIRE 16 -1 (-6050 3150)(-5025 3150);
FORCEPROP 0 LAST SIG_NAME TP_CPU1_DMI_RX_DN3
J 0
(-5985 3160);
DISPLAY 0.617021 (-5985 3160);
PAINT ORANGE (-5985 3160);
FORCEPROP 2 LASTPROP $XRERR UNIQUE?
J 0
(-6290 3150);
DISPLAY 0.638298 (-6290 3150);
PAINT MONO (-6290 3150);
DISPLAY INVISIBLE (-6290 3150);
WIRE 16 -1 (-6050 3000)(-5025 3000);
FORCEPROP 0 LAST SIG_NAME TP_CPU1_DMI_RX_DN0
J 0
(-5985 3010);
DISPLAY 0.617021 (-5985 3010);
PAINT ORANGE (-5985 3010);
FORCEPROP 2 LASTPROP $XRERR UNIQUE?
J 0
(-6290 3000);
DISPLAY 0.638298 (-6290 3000);
PAINT MONO (-6290 3000);
DISPLAY INVISIBLE (-6290 3000);
WIRE 16 -1 (-6050 2600)(-5025 2600);
FORCEPROP 2 LAST SIG_NAME TP_IRQ_CPU1_CD_HFI0_N
J 0
(-6000 2610);
DISPLAY 0.617021 (-6000 2610);
PAINT ORANGE (-6000 2610);
FORCEPROP 2 LASTPROP $XRERR UNIQUE?
J 0
(-6290 2600);
DISPLAY 0.638298 (-6290 2600);
PAINT MONO (-6290 2600);
DISPLAY INVISIBLE (-6290 2600);
WIRE 16 -1 (-6050 2350)(-5025 2350);
FORCEPROP 2 LAST SIG_NAME JTAG_MCP_TCK
J 0
(-5985 2360);
DISPLAY 0.617021 (-5985 2360);
PAINT ORANGE (-5985 2360);
WIRE 16 -1 (-5025 2300)(-6050 2300);
FORCEPROP 2 LAST SIG_NAME JTAG_MCP_CPU1_TDI
J 0
(-5985 2310);
DISPLAY 0.617021 (-5985 2310);
PAINT ORANGE (-5985 2310);
WIRE 16 -1 (-5025 2250)(-6050 2250);
FORCEPROP 2 LAST SIG_NAME JTAG_MCP_TMS
J 0
(-5985 2260);
DISPLAY 0.617021 (-5985 2260);
PAINT ORANGE (-5985 2260);
WIRE 16 -1 (-5025 2200)(-6050 2200);
FORCEPROP 2 LAST SIG_NAME JTAG_MCP_TRST_N
J 0
(-5985 2210);
DISPLAY 0.617021 (-5985 2210);
PAINT ORANGE (-5985 2210);
WIRE 16 -1 (-5025 2100)(-6050 2100);
FORCEPROP 2 LAST SIG_NAME TP_CPU1_RSVD_183
J 0
(-6000 2110);
DISPLAY 0.617021 (-6000 2110);
PAINT ORANGE (-6000 2110);
FORCEPROP 2 LASTPROP $XRERR UNIQUE?
J 0
(-6290 2100);
DISPLAY 0.638298 (-6290 2100);
PAINT MONO (-6290 2100);
DISPLAY INVISIBLE (-6290 2100);
WIRE 16 -1 (-5025 1900)(-6050 1900);
FORCEPROP 2 LAST SIG_NAME TP_CPU1_RSVD_180
J 0
(-6000 1910);
DISPLAY 0.617021 (-6000 1910);
PAINT ORANGE (-6000 1910);
FORCEPROP 2 LASTPROP $XRERR UNIQUE?
J 0
(-6290 1900);
DISPLAY 0.638298 (-6290 1900);
PAINT MONO (-6290 1900);
DISPLAY INVISIBLE (-6290 1900);
WIRE 16 -1 (-5025 1850)(-6050 1850);
FORCEPROP 2 LAST SIG_NAME TP_CPU1_RSVD_179
J 0
(-6000 1860);
DISPLAY 0.617021 (-6000 1860);
PAINT ORANGE (-6000 1860);
FORCEPROP 2 LASTPROP $XRERR UNIQUE?
J 0
(-6290 1850);
DISPLAY 0.638298 (-6290 1850);
PAINT MONO (-6290 1850);
DISPLAY INVISIBLE (-6290 1850);
WIRE 16 -1 (-5025 1750)(-6050 1750);
FORCEPROP 2 LAST SIG_NAME TP_CPU1_RSVD_177
J 0
(-6000 1760);
DISPLAY 0.617021 (-6000 1760);
PAINT ORANGE (-6000 1760);
FORCEPROP 2 LASTPROP $XRERR UNIQUE?
J 0
(-6290 1750);
DISPLAY 0.638298 (-6290 1750);
PAINT MONO (-6290 1750);
DISPLAY INVISIBLE (-6290 1750);
WIRE 16 -1 (-5025 1650)(-6050 1650);
FORCEPROP 2 LAST SIG_NAME TP_CPU1_RSVD_175
J 0
(-6000 1660);
DISPLAY 0.617021 (-6000 1660);
PAINT ORANGE (-6000 1660);
FORCEPROP 2 LASTPROP $XRERR UNIQUE?
J 0
(-6290 1650);
DISPLAY 0.638298 (-6290 1650);
PAINT MONO (-6290 1650);
DISPLAY INVISIBLE (-6290 1650);
WIRE 16 -1 (-5025 1600)(-6050 1600);
FORCEPROP 2 LAST SIG_NAME TP_CPU1_RSVD_174
J 0
(-6000 1610);
DISPLAY 0.617021 (-6000 1610);
PAINT ORANGE (-6000 1610);
FORCEPROP 2 LASTPROP $XRERR UNIQUE?
J 0
(-6290 1600);
DISPLAY 0.638298 (-6290 1600);
PAINT MONO (-6290 1600);
DISPLAY INVISIBLE (-6290 1600);
WIRE 16 -1 (-5025 1700)(-6050 1700);
FORCEPROP 2 LAST SIG_NAME TP_CPU1_RSVD_176
J 0
(-6000 1710);
DISPLAY 0.617021 (-6000 1710);
PAINT ORANGE (-6000 1710);
FORCEPROP 2 LASTPROP $XRERR UNIQUE?
J 0
(-6290 1700);
DISPLAY 0.638298 (-6290 1700);
PAINT MONO (-6290 1700);
DISPLAY INVISIBLE (-6290 1700);
WIRE 16 -1 (-5025 2050)(-6050 2050);
FORCEPROP 2 LAST SIG_NAME TP_CPU1_RSVD_182
J 0
(-6000 2060);
DISPLAY 0.617021 (-6000 2060);
PAINT ORANGE (-6000 2060);
FORCEPROP 2 LASTPROP $XRERR UNIQUE?
J 0
(-6290 2050);
DISPLAY 0.638298 (-6290 2050);
PAINT MONO (-6290 2050);
DISPLAY INVISIBLE (-6290 2050);
WIRE 16 -1 (-5025 1800)(-6050 1800);
FORCEPROP 2 LAST SIG_NAME TP_CPU1_RSVD_178
J 0
(-6000 1810);
DISPLAY 0.617021 (-6000 1810);
PAINT ORANGE (-6000 1810);
FORCEPROP 2 LASTPROP $XRERR UNIQUE?
J 0
(-6290 1800);
DISPLAY 0.638298 (-6290 1800);
PAINT MONO (-6290 1800);
DISPLAY INVISIBLE (-6290 1800);
WIRE 16 -1 (-5025 1950)(-6050 1950);
FORCEPROP 2 LAST SIG_NAME TP_CPU1_RSVD_181
J 0
(-6000 1960);
DISPLAY 0.617021 (-6000 1960);
PAINT ORANGE (-6000 1960);
FORCEPROP 2 LASTPROP $XRERR UNIQUE?
J 0
(-6290 1950);
DISPLAY 0.638298 (-6290 1950);
PAINT MONO (-6290 1950);
DISPLAY INVISIBLE (-6290 1950);
WIRE 16 -1 (-5025 2900)(-6050 2900);
FORCEPROP 2 LAST SIG_NAME CLK_156M_OSC_CPU1_HFI_DP
J 0
(-5985 2910);
DISPLAY 0.617021 (-5985 2910);
PAINT ORANGE (-5985 2910);
WIRE 16 -1 (-6050 2850)(-5025 2850);
FORCEPROP 2 LAST SIG_NAME CLK_156M_OSC_CPU1_HFI_DN
J 0
(-5985 2860);
DISPLAY 0.617021 (-5985 2860);
PAINT ORANGE (-5985 2860);
WIRE 16 -1 (-6050 3050)(-5025 3050);
FORCEPROP 0 LAST SIG_NAME TP_CPU1_DMI_RX_DN1
J 0
(-5985 3060);
DISPLAY 0.617021 (-5985 3060);
PAINT ORANGE (-5985 3060);
FORCEPROP 2 LASTPROP $XRERR UNIQUE?
J 0
(-6290 3050);
DISPLAY 0.638298 (-6290 3050);
PAINT MONO (-6290 3050);
DISPLAY INVISIBLE (-6290 3050);
WIRE 16 -1 (-5025 3100)(-6050 3100);
FORCEPROP 0 LAST SIG_NAME TP_CPU1_DMI_RX_DN2
J 0
(-5985 3110);
DISPLAY 0.617021 (-5985 3110);
PAINT ORANGE (-5985 3110);
FORCEPROP 2 LASTPROP $XRERR UNIQUE?
J 0
(-6290 3100);
DISPLAY 0.638298 (-6290 3100);
PAINT MONO (-6290 3100);
DISPLAY INVISIBLE (-6290 3100);
WIRE 16 -1 (-6050 3350)(-5025 3350);
FORCEPROP 0 LAST SIG_NAME TP_CPU1_DMI_RX_DP2
J 0
(-5985 3360);
DISPLAY 0.617021 (-5985 3360);
PAINT ORANGE (-5985 3360);
FORCEPROP 2 LASTPROP $XRERR UNIQUE?
J 0
(-6290 3350);
DISPLAY 0.638298 (-6290 3350);
PAINT MONO (-6290 3350);
DISPLAY INVISIBLE (-6290 3350);
WIRE 16 -1 (-5025 2450)(-6050 2450);
FORCEPROP 2 LAST SIG_NAME TP_SMB_CPU1_CD_HFI0_I2CDAT
J 0
(-6000 2460);
DISPLAY 0.617021 (-6000 2460);
PAINT ORANGE (-6000 2460);
FORCEPROP 2 LASTPROP $XRERR UNIQUE?
J 0
(-6290 2450);
DISPLAY 0.638298 (-6290 2450);
PAINT MONO (-6290 2450);
DISPLAY INVISIBLE (-6290 2450);
WIRE 16 -1 (-6050 2500)(-5025 2500);
FORCEPROP 2 LAST SIG_NAME TP_SMB_CPU1_CD_HFI0_I2CCLK
J 0
(-6000 2510);
DISPLAY 0.617021 (-6000 2510);
PAINT ORANGE (-6000 2510);
FORCEPROP 2 LASTPROP $XRERR UNIQUE?
J 0
(-6290 2500);
DISPLAY 0.638298 (-6290 2500);
PAINT MONO (-6290 2500);
DISPLAY INVISIBLE (-6290 2500);
WIRE 16 -1 (-6050 2650)(-5025 2650);
FORCEPROP 2 LAST SIG_NAME TP_LED_CPU1_CD_HFI0_N
J 0
(-6000 2660);
DISPLAY 0.617021 (-6000 2660);
PAINT ORANGE (-6000 2660);
FORCEPROP 2 LASTPROP $XRERR UNIQUE?
J 0
(-6290 2650);
DISPLAY 0.638298 (-6290 2650);
PAINT MONO (-6290 2650);
DISPLAY INVISIBLE (-6290 2650);
WIRE 16 -1 (-5025 2750)(-6050 2750);
FORCEPROP 2 LAST SIG_NAME TP_RST_CPU1_CD_HFI0_N
J 0
(-6000 2760);
DISPLAY 0.617021 (-6000 2760);
PAINT ORANGE (-6000 2760);
FORCEPROP 2 LASTPROP $XRERR UNIQUE?
J 0
(-6290 2750);
DISPLAY 0.638298 (-6290 2750);
PAINT MONO (-6290 2750);
DISPLAY INVISIBLE (-6290 2750);
WIRE 16 -1 (-5025 2700)(-6050 2700);
FORCEPROP 2 LAST SIG_NAME TP_FM_CPU1_CD_HFI0_MODPRST_N
J 0
(-6000 2710);
DISPLAY 0.617021 (-6000 2710);
PAINT ORANGE (-6000 2710);
FORCEPROP 2 LASTPROP $XRERR UNIQUE?
J 0
(-6290 2700);
DISPLAY 0.638298 (-6290 2700);
PAINT MONO (-6290 2700);
DISPLAY INVISIBLE (-6290 2700);
WIRE 16 -1 (-2100 1600)(-3125 1600);
FORCEPROP 2 LAST SIG_NAME TP_CPU1_RSVD_173
J 0
(-2950 1610);
DISPLAY 0.617021 (-2950 1610);
PAINT ORANGE (-2950 1610);
FORCEPROP 2 LASTPROP $XRERR UNIQUE?
J 0
(-2070 1600);
DISPLAY 0.638298 (-2070 1600);
PAINT MONO (-2070 1600);
DISPLAY INVISIBLE (-2070 1600);
WIRE 16 -1 (-2100 1650)(-3125 1650);
FORCEPROP 2 LAST SIG_NAME TP_CPU1_RSVD_184
J 0
(-2950 1660);
DISPLAY 0.617021 (-2950 1660);
PAINT ORANGE (-2950 1660);
FORCEPROP 2 LASTPROP $XRERR UNIQUE?
J 0
(-2070 1650);
DISPLAY 0.638298 (-2070 1650);
PAINT MONO (-2070 1650);
DISPLAY INVISIBLE (-2070 1650);
WIRE 16 -1 (-2100 1700)(-3125 1700);
FORCEPROP 2 LAST SIG_NAME TP_CPU1_RSVD_186
J 0
(-2950 1710);
DISPLAY 0.617021 (-2950 1710);
PAINT ORANGE (-2950 1710);
FORCEPROP 2 LASTPROP $XRERR UNIQUE?
J 0
(-2070 1700);
DISPLAY 0.638298 (-2070 1700);
PAINT MONO (-2070 1700);
DISPLAY INVISIBLE (-2070 1700);
WIRE 16 -1 (-2100 1850)(-3125 1850);
FORCEPROP 2 LAST SIG_NAME TP_CPU1_RSVD_189
J 0
(-2950 1860);
DISPLAY 0.617021 (-2950 1860);
PAINT ORANGE (-2950 1860);
FORCEPROP 2 LASTPROP $XRERR UNIQUE?
J 0
(-2070 1850);
DISPLAY 0.638298 (-2070 1850);
PAINT MONO (-2070 1850);
DISPLAY INVISIBLE (-2070 1850);
WIRE 16 -1 (-2100 1900)(-3125 1900);
FORCEPROP 2 LAST SIG_NAME TP_CPU1_RSVD_190
J 0
(-2950 1910);
DISPLAY 0.617021 (-2950 1910);
PAINT ORANGE (-2950 1910);
FORCEPROP 2 LASTPROP $XRERR UNIQUE?
J 0
(-2070 1900);
DISPLAY 0.638298 (-2070 1900);
PAINT MONO (-2070 1900);
DISPLAY INVISIBLE (-2070 1900);
WIRE 16 -1 (-2100 2200)(-3125 2200);
FORCEPROP 2 LAST SIG_NAME JTAG_MCP_CPU1_TDO
J 0
(-2935 2210);
DISPLAY 0.617021 (-2935 2210);
PAINT ORANGE (-2935 2210);
WIRE 16 -1 (-2100 2300)(-3125 2300);
FORCEPROP 2 LAST SIG_NAME RST_CD_CPU1_POR_N
J 0
(-2950 2310);
DISPLAY 0.617021 (-2950 2310);
PAINT ORANGE (-2950 2310);
WIRE 16 -1 (-2100 2450)(-3125 2450);
FORCEPROP 2 LAST SIG_NAME TP_CD_HFI1_CPU1_I2CDAT
J 0
(-2950 2460);
DISPLAY 0.617021 (-2950 2460);
PAINT ORANGE (-2950 2460);
FORCEPROP 2 LASTPROP $XRERR UNIQUE?
J 0
(-2070 2450);
DISPLAY 0.638298 (-2070 2450);
PAINT MONO (-2070 2450);
DISPLAY INVISIBLE (-2070 2450);
WIRE 16 -1 (-2100 2500)(-3125 2500);
FORCEPROP 2 LAST SIG_NAME TP_CD_HFI1_CPU1_I2CLK
J 0
(-2950 2510);
DISPLAY 0.617021 (-2950 2510);
PAINT ORANGE (-2950 2510);
FORCEPROP 2 LASTPROP $XRERR UNIQUE?
J 0
(-2070 2500);
DISPLAY 0.638298 (-2070 2500);
PAINT MONO (-2070 2500);
DISPLAY INVISIBLE (-2070 2500);
WIRE 16 -1 (-2100 2600)(-3125 2600);
FORCEPROP 2 LAST SIG_NAME TP_CD_HFI1_CPU1_INT_N
J 0
(-2950 2610);
DISPLAY 0.617021 (-2950 2610);
PAINT ORANGE (-2950 2610);
FORCEPROP 2 LASTPROP $XRERR UNIQUE?
J 0
(-2070 2600);
DISPLAY 0.638298 (-2070 2600);
PAINT MONO (-2070 2600);
DISPLAY INVISIBLE (-2070 2600);
WIRE 16 -1 (-3125 2650)(-2100 2650);
FORCEPROP 2 LAST SIG_NAME TP_CD_HFI1_CPU1_LED_N
J 0
(-2950 2660);
DISPLAY 0.617021 (-2950 2660);
PAINT ORANGE (-2950 2660);
FORCEPROP 2 LASTPROP $XRERR UNIQUE?
J 0
(-2070 2650);
DISPLAY 0.638298 (-2070 2650);
PAINT MONO (-2070 2650);
DISPLAY INVISIBLE (-2070 2650);
WIRE 16 -1 (-2100 2700)(-3125 2700);
FORCEPROP 2 LAST SIG_NAME TP_CD_HFI1_CPU1_MODPRST_N
J 0
(-2950 2710);
DISPLAY 0.617021 (-2950 2710);
PAINT ORANGE (-2950 2710);
FORCEPROP 2 LASTPROP $XRERR UNIQUE?
J 0
(-2070 2700);
DISPLAY 0.638298 (-2070 2700);
PAINT MONO (-2070 2700);
DISPLAY INVISIBLE (-2070 2700);
WIRE 16 -1 (-2100 2750)(-3125 2750);
FORCEPROP 2 LAST SIG_NAME TP_CD_HFI1_CPU1_RESET_N
J 0
(-2950 2760);
DISPLAY 0.617021 (-2950 2760);
PAINT ORANGE (-2950 2760);
FORCEPROP 2 LASTPROP $XRERR UNIQUE?
J 0
(-2070 2750);
DISPLAY 0.638298 (-2070 2750);
PAINT MONO (-2070 2750);
DISPLAY INVISIBLE (-2070 2750);
WIRE 16 -1 (-2100 2900)(-3125 2900);
FORCEPROP 2 LAST SIG_NAME CLK_100M_CPU1_PE_REFCLK_DP
J 0
(-2925 2910);
DISPLAY 0.617021 (-2925 2910);
PAINT ORANGE (-2925 2910);
WIRE 16 -1 (-2100 2850)(-3125 2850);
FORCEPROP 0 LAST SIG_NAME CLK_100M_CPU1_PE_REFCLK_DN
J 0
(-2925 2860);
DISPLAY 0.617021 (-2925 2860);
PAINT ORANGE (-2925 2860);
WIRE 16 -1 (-3125 3400)(-2100 3400);
FORCEPROP 0 LAST SIG_NAME TP_CPU1_DMI_TX_DP3
J 0
(-2935 3410);
DISPLAY 0.617021 (-2935 3410);
PAINT ORANGE (-2935 3410);
FORCEPROP 2 LASTPROP $XRERR UNIQUE?
J 0
(-2070 3400);
DISPLAY 0.638298 (-2070 3400);
PAINT MONO (-2070 3400);
DISPLAY INVISIBLE (-2070 3400);
WIRE 16 -1 (-3125 3300)(-2100 3300);
FORCEPROP 0 LAST SIG_NAME TP_CPU1_DMI_TX_DP1
J 0
(-2935 3310);
DISPLAY 0.617021 (-2935 3310);
PAINT ORANGE (-2935 3310);
FORCEPROP 2 LASTPROP $XRERR UNIQUE?
J 0
(-2070 3300);
DISPLAY 0.638298 (-2070 3300);
PAINT MONO (-2070 3300);
DISPLAY INVISIBLE (-2070 3300);
WIRE 16 -1 (-3125 3150)(-2100 3150);
FORCEPROP 0 LAST SIG_NAME TP_CPU1_DMI_TX_DN3
J 0
(-2935 3160);
DISPLAY 0.617021 (-2935 3160);
PAINT ORANGE (-2935 3160);
FORCEPROP 2 LASTPROP $XRERR UNIQUE?
J 0
(-2070 3150);
DISPLAY 0.638298 (-2070 3150);
PAINT MONO (-2070 3150);
DISPLAY INVISIBLE (-2070 3150);
WIRE 16 -1 (-2100 3100)(-3125 3100);
FORCEPROP 0 LAST SIG_NAME TP_CPU1_DMI_TX_DN2
J 0
(-2935 3110);
DISPLAY 0.617021 (-2935 3110);
PAINT ORANGE (-2935 3110);
FORCEPROP 2 LASTPROP $XRERR UNIQUE?
J 0
(-2070 3100);
DISPLAY 0.638298 (-2070 3100);
PAINT MONO (-2070 3100);
DISPLAY INVISIBLE (-2070 3100);
WIRE 16 -1 (-3125 3050)(-2100 3050);
FORCEPROP 0 LAST SIG_NAME TP_CPU1_DMI_TX_DN1
J 0
(-2935 3060);
DISPLAY 0.617021 (-2935 3060);
PAINT ORANGE (-2935 3060);
FORCEPROP 2 LASTPROP $XRERR UNIQUE?
J 0
(-2070 3050);
DISPLAY 0.638298 (-2070 3050);
PAINT MONO (-2070 3050);
DISPLAY INVISIBLE (-2070 3050);
WIRE 16 -1 (-2100 3000)(-3125 3000);
FORCEPROP 0 LAST SIG_NAME TP_CPU1_DMI_TX_DN0
J 0
(-2935 3010);
DISPLAY 0.617021 (-2935 3010);
PAINT ORANGE (-2935 3010);
FORCEPROP 2 LASTPROP $XRERR UNIQUE?
J 0
(-2070 3000);
DISPLAY 0.638298 (-2070 3000);
PAINT MONO (-2070 3000);
DISPLAY INVISIBLE (-2070 3000);
DOT 1 (-3000 1800);
DOT 1 (-3000 2050);
DOT 1 (-3000 2100);
DOT 1 (-1425 2100);
FORCENOTE
ROOM=CPU1
(-7975 375) 0;
DISPLAY LEFT (-7975 375);
DISPLAY 1.723404 (-7975 375);
PAINT PURPLE (-7975 375);
FORCENOTE
BOM_COST=PROC_SOCKET
(-7975 250) 0;
DISPLAY LEFT (-7975 250);
DISPLAY 1.723404 (-7975 250);
PAINT PURPLE (-7975 250);
QUIT
